(kicad_pcb
	(version 20260206)
	(generator "pcbnew")
	(generator_version "10.0")
	(general
		(thickness 1.6)
		(legacy_teardrops no)
	)
	(paper "A4")
	(title_block
		(title "04192023_DAF0TMB3IC0_F0TG_MB_C_brd_V02_OCP.brd")
		(comment 1 "Grand Teton / footprints 2873-2878 of 8354")
	)
	(layers
		(0 "F.Cu" signal "TOP")
		(4 "In1.Cu" signal "GND")
		(6 "In2.Cu" signal "IN1")
		(8 "In3.Cu" signal "GND1")
		(10 "In4.Cu" signal "IN2")
		(12 "In5.Cu" signal "GND2")
		(14 "In6.Cu" signal "IN3")
		(16 "In7.Cu" signal "GND3")
		(18 "In8.Cu" signal "VCC")
		(20 "In9.Cu" signal "VCC1")
		(22 "In10.Cu" signal "GND4")
		(24 "In11.Cu" signal "IN4")
		(26 "In12.Cu" signal "GND5")
		(28 "In13.Cu" signal "IN5")
		(30 "In14.Cu" signal "GND6")
		(32 "In15.Cu" signal "IN6")
		(34 "In16.Cu" signal "GND7")
		(2 "B.Cu" signal "BOTTOM")
		(9 "F.Adhes" user "F.Adhesive")
		(11 "B.Adhes" user "B.Adhesive")
		(13 "F.Paste" user "Package Geometry/Pastemask Top")
		(15 "B.Paste" user "Package Geometry/Pastemask Bottom")
		(5 "F.SilkS" user "Ref Des/Silkscreen Top")
		(7 "B.SilkS" user "Ref Des/Silkscreen Bottom")
		(1 "F.Mask" user "Board Geometry/Soldermask Top")
		(3 "B.Mask" user "Board Geometry/Soldermask Bottom")
		(17 "Dwgs.User" user "User.Drawings")
		(19 "Cmts.User" user "User.Comments")
		(21 "Eco1.User" user "User.Eco1")
		(23 "Eco2.User" user "User.Eco2")
		(25 "Edge.Cuts" user "Board Geometry/Outline")
		(27 "Margin" user)
		(31 "F.CrtYd" user "Package Geometry/Place Bound Top")
		(29 "B.CrtYd" user "Package Geometry/Place Bound Bottom")
		(35 "F.Fab" user "Ref Des/Assembly Top")
		(33 "B.Fab" user "Ref Des/Assembly Bottom")
	)
	(footprint ""
		(layer "F.Cu")
		(at 275.422106 -346.71635)
		(property "Reference" "PU20"
			(at -1.737106 -7.58698 0)
			(unlocked yes)
			(layer "F.SilkS")
			(effects
				(font
					(size 0.7874 0.5842)
					(thickness 0.1524)
				)
				(justify left)
			)
		)
		(property "Value" ""
			(at 0 0 0)
			(layer "F.Fab")
			(effects
				(font
					(size 1.27 1.27)
				)
			)
		)
		(duplicate_pad_numbers_are_jumpers no)
		(fp_line
			(start -2.500122 -2.999994)
			(end -2.24409 -2.999994)
			(stroke
				(width 0.1524)
				(type default)
			)
			(layer "F.SilkS")
		)
		(fp_line
			(start -2.500122 -2.529078)
			(end -2.500122 -2.999994)
			(stroke
				(width 0.1524)
				(type default)
			)
			(layer "F.SilkS")
		)
		(fp_line
			(start -2.500122 0.6604)
			(end -2.500122 0.229108)
			(stroke
				(width 0.1524)
				(type default)
			)
			(layer "F.SilkS")
		)
		(fp_line
			(start -2.500122 2.999994)
			(end -2.500122 2.339594)
			(stroke
				(width 0.1524)
				(type default)
			)
			(layer "F.SilkS")
		)
		(fp_line
			(start -2.2987 2.999994)
			(end -2.500122 2.999994)
			(stroke
				(width 0.1524)
				(type default)
			)
			(layer "F.SilkS")
		)
		(fp_line
			(start 2.31394 -2.999994)
			(end 2.500122 -2.999994)
			(stroke
				(width 0.1524)
				(type default)
			)
			(layer "F.SilkS")
		)
		(fp_line
			(start 2.500122 -2.999994)
			(end 2.500122 -2.44348)
			(stroke
				(width 0.1524)
				(type default)
			)
			(layer "F.SilkS")
		)
		(fp_line
			(start 2.500122 2.339594)
			(end 2.500122 2.999994)
			(stroke
				(width 0.1524)
				(type default)
			)
			(layer "F.SilkS")
		)
		(fp_line
			(start 2.500122 2.999994)
			(end 2.2987 2.999994)
			(stroke
				(width 0.1524)
				(type default)
			)
			(layer "F.SilkS")
		)
		(fp_poly
			(pts
				(xy -3.464814 -2.702052) (xy -2.983484 -3.183382) (xy -2.742946 -2.461514)
			)
			(stroke
				(width 0)
				(type default)
			)
			(fill yes)
			(layer "F.SilkS")
		)
		(fp_line
			(start -2.500122 -2.999994)
			(end 2.500122 -2.999994)
			(stroke
				(width 0.1)
				(type default)
			)
			(layer "F.Fab")
		)
		(fp_line
			(start -2.500122 2.999994)
			(end -2.500122 -2.999994)
			(stroke
				(width 0.1)
				(type default)
			)
			(layer "F.Fab")
		)
		(fp_line
			(start 2.500122 -2.999994)
			(end 2.500122 2.999994)
			(stroke
				(width 0.1)
				(type default)
			)
			(layer "F.Fab")
		)
		(fp_line
			(start 2.500122 2.999994)
			(end -2.500122 2.999994)
			(stroke
				(width 0.1)
				(type default)
			)
			(layer "F.Fab")
		)
		(fp_poly
			(pts
				(xy -4.218432 -2.783078) (xy -4.218432 -1.767078) (xy -3.202432 -2.275078)
			)
			(stroke
				(width 0)
				(type default)
			)
			(fill yes)
			(layer "F.Fab")
		)
		(pad "1" smd rect
			(at -2.400046 -2.275078 90)
			(size 0.2286 0.6096)
			(layers "F.Cu" "F.Mask" "F.Paste")
			(net "PVDDIO_P0_VOS4")
		)
		(pad "2" smd rect
			(at -2.400046 -1.82499 90)
			(size 0.2286 0.6096)
			(layers "F.Cu" "F.Mask" "F.Paste")
			(net "GND")
		)
		(pad "3" smd rect
			(at -2.400046 -1.374902 90)
			(size 0.2286 0.6096)
			(layers "F.Cu" "F.Mask" "F.Paste")
			(net "PVDDIO_P0_VCC4")
		)
		(pad "4" smd rect
			(at -2.400046 -0.925068 90)
			(size 0.2286 0.6096)
			(layers "F.Cu" "F.Mask" "F.Paste")
			(net "PVDDCR_CPU1_P0_PVCC")
		)
		(pad "5" smd rect
			(at -2.400046 -0.47498 90)
			(size 0.2286 0.6096)
			(layers "F.Cu" "F.Mask" "F.Paste")
			(net "GND")
		)
		(pad "6" smd rect
			(at -2.400046 -0.024892 90)
			(size 0.2286 0.6096)
			(layers "F.Cu" "F.Mask" "F.Paste")
			(net "NC_PVDDIO_P0_GL1_4")
		)
		(pad "7_9-20_24" smd circle
			(at 0 1.150112 90)
			(size 0 0)
			(layers "F.Cu" "F.Mask" "F.Paste")
			(net "GND")
		)
		(pad "10_19" smd rect
			(at 0 2.899918 90)
			(size 0.6096 4.318)
			(layers "F.Cu" "F.Mask" "F.Paste")
			(net "SW_PVDDIO_P0_SW4")
		)
		(pad "25_29" smd rect
			(at 1.549908 -1.279906 270)
			(size 2.0574 2.3114)
			(layers "F.Cu" "F.Mask" "F.Paste")
			(net "SW_P12V_AUX_PVDDIO_P0_FLT")
		)
		(pad "30" smd rect
			(at 2.05994 -2.899918)
			(size 0.2286 0.6096)
			(layers "F.Cu" "F.Mask" "F.Paste")
			(net "SW_P12V_AUX_PVDDIO_P0_FLT")
		)
		(pad "31" smd rect
			(at 1.610106 -2.899918)
			(size 0.2286 0.6096)
			(layers "F.Cu" "F.Mask" "F.Paste")
			(net "NC_PVDDIO_P0_DNC4")
		)
		(pad "32" smd rect
			(at 1.160018 -2.899918)
			(size 0.2286 0.6096)
			(layers "F.Cu" "F.Mask" "F.Paste")
			(net "SW_PVDDIO_P0_BOOTR4")
		)
		(pad "33" smd rect
			(at 0.70993 -2.899918)
			(size 0.2286 0.6096)
			(layers "F.Cu" "F.Mask" "F.Paste")
			(net "SW_PVDDIO_P0_BOOT4")
		)
		(pad "34" smd rect
			(at 0.260096 -2.899918)
			(size 0.2286 0.6096)
			(layers "F.Cu" "F.Mask" "F.Paste")
			(net "PVDDIO_P0_PWM4")
		)
		(pad "35" smd rect
			(at -0.189992 -2.899918)
			(size 0.2286 0.6096)
			(layers "F.Cu" "F.Mask" "F.Paste")
			(net "PVDDIO_P0_VCC4")
		)
		(pad "36" smd rect
			(at -0.64008 -2.899918)
			(size 0.2286 0.6096)
			(layers "F.Cu" "F.Mask" "F.Paste")
			(net "PVDDIO_P0_TEMP1")
		)
		(pad "37" smd rect
			(at -1.089914 -2.899918)
			(size 0.2286 0.6096)
			(layers "F.Cu" "F.Mask" "F.Paste")
			(net "PVDDIO_P0_LSET4")
		)
		(pad "38" smd rect
			(at -1.540002 -2.899918)
			(size 0.2286 0.6096)
			(layers "F.Cu" "F.Mask" "F.Paste")
			(net "PVDDIO_P0_IMON4")
		)
		(pad "39" smd rect
			(at -1.99009 -2.899918)
			(size 0.2286 0.6096)
			(layers "F.Cu" "F.Mask" "F.Paste")
			(net "PVDDCR_CPU1_P0_VCCS")
		)
		(pad "40" smd rect
			(at -0.87503 -1.27508)
			(size 1.7526 1.9558)
			(layers "F.Cu" "F.Mask" "F.Paste")
			(net "GND")
		)
		(pad "41" smd rect
			(at -1.525016 0.249936 270)
			(size 0.3048 0.4572)
			(layers "F.Cu" "F.Mask" "F.Paste")
			(net "NC_PVDDIO_P0_GL2_4")
		)
		(zone
			(layer "F.Cu")
			(hatch none 0.5)
			(connect_pads
				(clearance 0)
			)
			(min_thickness 0.25)
			(keepout
				(tracks not_allowed)
				(vias allowed)
				(pads allowed)
				(copperpour not_allowed)
				(footprints allowed)
			)
			(placement
				(enabled no)
				(sheetname "")
			)
			(fill
				(thermal_gap 0.5)
				(thermal_bridge_width 0.5)
				(island_removal_mode 0)
			)
			(polygon
				(pts
					(xy 272.921984 -344.138758) (xy 272.921984 -344.465656) (xy 277.922228 -344.465656) (xy 277.922228 -344.141806)
					(xy 277.631906 -344.141806) (xy 277.631906 -344.172032) (xy 273.212306 -344.172032) (xy 273.212306 -344.138758)
				)
			)
		)
		(zone
			(layer "F.Cu")
			(hatch none 0.5)
			(connect_pads
				(clearance 0)
			)
			(min_thickness 0.25)
			(keepout
				(tracks not_allowed)
				(vias allowed)
				(pads allowed)
				(copperpour not_allowed)
				(footprints allowed)
			)
			(placement
				(enabled no)
				(sheetname "")
			)
			(fill
				(thermal_gap 0.5)
				(thermal_bridge_width 0.5)
				(island_removal_mode 0)
			)
			(polygon
				(pts
					(xy 275.474176 -346.96273) (xy 275.474176 -349.02013) (xy 273.619976 -349.02013) (xy 273.619976 -348.779084)
					(xy 273.37766 -348.779084) (xy 273.37766 -349.260668) (xy 277.21814 -349.260668) (xy 277.21814 -349.075756)
					(xy 275.765514 -349.075756) (xy 275.765514 -346.916756) (xy 277.922228 -346.916756) (xy 277.922228 -346.667074)
					(xy 275.769832 -346.667074)
				)
			)
		)
	)
	(footprint ""
		(layer "F.Cu")
		(at 413.93364 -378.95403 -90)
		(property "Reference" "C851"
			(at 0 0 270)
			(layer "F.SilkS")
			(hide yes)
			(effects
				(font
					(size 1.27 1.27)
				)
			)
		)
		(property "Value" ""
			(at 0 0 270)
			(layer "F.Fab")
			(effects
				(font
					(size 1.27 1.27)
				)
			)
		)
		(duplicate_pad_numbers_are_jumpers no)
		(fp_line
			(start -0.299974 0.150114)
			(end -0.299974 -0.150114)
			(stroke
				(width 0.1)
				(type default)
			)
			(layer "F.Fab")
		)
		(fp_line
			(start 0.299974 0.150114)
			(end -0.299974 0.150114)
			(stroke
				(width 0.1)
				(type default)
			)
			(layer "F.Fab")
		)
		(fp_line
			(start -0.299974 -0.150114)
			(end 0.299974 -0.150114)
			(stroke
				(width 0.1)
				(type default)
			)
			(layer "F.Fab")
		)
		(fp_line
			(start 0.299974 -0.150114)
			(end 0.299974 0.150114)
			(stroke
				(width 0.1)
				(type default)
			)
			(layer "F.Fab")
		)
		(pad "1" smd rect
			(at -0.2667 0 270)
			(size 0.3048 0.381)
			(layers "F.Cu" "F.Mask" "F.Paste")
			(net "P5E_CPU0_P2_TX_C_DP<9>")
		)
		(pad "2" smd rect
			(at 0.2667 0 270)
			(size 0.3048 0.381)
			(layers "F.Cu" "F.Mask" "F.Paste")
			(net "P5E_CPU0_P2_TX_DP<9>")
		)
	)
	(footprint ""
		(layer "F.Cu")
		(at 445.252602 -418.17671 -90)
		(property "Reference" "PR6611"
			(at 0 0 270)
			(layer "F.SilkS")
			(hide yes)
			(effects
				(font
					(size 1.27 1.27)
				)
			)
		)
		(property "Value" ""
			(at 0 0 270)
			(layer "F.Fab")
			(effects
				(font
					(size 1.27 1.27)
				)
			)
		)
		(duplicate_pad_numbers_are_jumpers no)
		(fp_line
			(start -0.7874 0.4064)
			(end -0.7874 -0.4064)
			(stroke
				(width 0.1524)
				(type default)
			)
			(layer "F.SilkS")
		)
		(fp_line
			(start 0.7874 0.4064)
			(end -0.7874 0.4064)
			(stroke
				(width 0.1524)
				(type default)
			)
			(layer "F.SilkS")
		)
		(fp_line
			(start -0.7874 -0.4064)
			(end 0.7874 -0.4064)
			(stroke
				(width 0.1524)
				(type default)
			)
			(layer "F.SilkS")
		)
		(fp_line
			(start 0.7874 -0.4064)
			(end 0.7874 0.4064)
			(stroke
				(width 0.1524)
				(type default)
			)
			(layer "F.SilkS")
		)
		(fp_line
			(start -0.67945 0.3048)
			(end -0.67945 -0.305054)
			(stroke
				(width 0.1)
				(type default)
			)
			(layer "F.Fab")
		)
		(fp_line
			(start -0.12065 0.3048)
			(end -0.67945 0.3048)
			(stroke
				(width 0.1)
				(type default)
			)
			(layer "F.Fab")
		)
		(fp_line
			(start 0.120396 0.3048)
			(end 0.120396 0.2794)
			(stroke
				(width 0.1)
				(type default)
			)
			(layer "F.Fab")
		)
		(fp_line
			(start 0.67945 0.3048)
			(end 0.120396 0.3048)
			(stroke
				(width 0.1)
				(type default)
			)
			(layer "F.Fab")
		)
		(fp_line
			(start -0.12065 0.2794)
			(end -0.12065 0.3048)
			(stroke
				(width 0.1)
				(type default)
			)
			(layer "F.Fab")
		)
		(fp_line
			(start 0.120396 0.2794)
			(end -0.12065 0.2794)
			(stroke
				(width 0.1)
				(type default)
			)
			(layer "F.Fab")
		)
		(fp_line
			(start -0.12065 -0.2794)
			(end 0.12065 -0.2794)
			(stroke
				(width 0.1)
				(type default)
			)
			(layer "F.Fab")
		)
		(fp_line
			(start 0.12065 -0.2794)
			(end 0.12065 -0.3048)
			(stroke
				(width 0.1)
				(type default)
			)
			(layer "F.Fab")
		)
		(fp_line
			(start 0.12065 -0.3048)
			(end 0.67945 -0.3048)
			(stroke
				(width 0.1)
				(type default)
			)
			(layer "F.Fab")
		)
		(fp_line
			(start 0.67945 -0.3048)
			(end 0.67945 0.3048)
			(stroke
				(width 0.1)
				(type default)
			)
			(layer "F.Fab")
		)
		(fp_line
			(start -0.67945 -0.305054)
			(end -0.12065 -0.305054)
			(stroke
				(width 0.1)
				(type default)
			)
			(layer "F.Fab")
		)
		(fp_line
			(start -0.12065 -0.305054)
			(end -0.12065 -0.2794)
			(stroke
				(width 0.1)
				(type default)
			)
			(layer "F.Fab")
		)
		(pad "1" smd circle
			(at -0.40005 0 270)
			(size 0 0)
			(layers "F.Cu" "F.Mask" "F.Paste")
			(net "NC_P0V9_RETIMER_CPU0_IMON5")
		)
		(pad "2" smd circle
			(at 0.40005 0 270)
			(size 0 0)
			(layers "F.Cu" "F.Mask" "F.Paste")
			(net "GND")
		)
	)
	(footprint ""
		(layer "F.Cu")
		(at 355.08057 -404.0124 -90)
		(property "Reference" "R1040"
			(at 0 0 270)
			(layer "F.SilkS")
			(hide yes)
			(effects
				(font
					(size 1.27 1.27)
				)
			)
		)
		(property "Value" ""
			(at 0 0 270)
			(layer "F.Fab")
			(effects
				(font
					(size 1.27 1.27)
				)
			)
		)
		(duplicate_pad_numbers_are_jumpers no)
		(fp_line
			(start -0.32512 0.175006)
			(end -0.32512 -0.175006)
			(stroke
				(width 0.1)
				(type default)
			)
			(layer "F.Fab")
		)
		(fp_line
			(start 0.32512 0.175006)
			(end -0.32512 0.175006)
			(stroke
				(width 0.1)
				(type default)
			)
			(layer "F.Fab")
		)
		(fp_line
			(start -0.32512 -0.175006)
			(end 0.32512 -0.175006)
			(stroke
				(width 0.1)
				(type default)
			)
			(layer "F.Fab")
		)
		(fp_line
			(start 0.32512 -0.175006)
			(end 0.32512 0.175006)
			(stroke
				(width 0.1)
				(type default)
			)
			(layer "F.Fab")
		)
		(pad "1" smd rect
			(at -0.2667 0 270)
			(size 0.3048 0.381)
			(layers "F.Cu" "F.Mask" "F.Paste")
			(net "P1V8_CPU0_RT_1D")
		)
		(pad "2" smd rect
			(at 0.2667 0 90)
			(size 0.3048 0.381)
			(layers "F.Cu" "F.Mask" "F.Paste")
			(net "RT_CPU0_P1_VQPS")
		)
	)
	(footprint ""
		(layer "F.Cu")
		(at 103.413814 -36.6522 180)
		(property "Reference" "R6326"
			(at 0 0 180)
			(layer "F.SilkS")
			(hide yes)
			(effects
				(font
					(size 1.27 1.27)
				)
			)
		)
		(property "Value" ""
			(at 0 0 180)
			(layer "F.Fab")
			(effects
				(font
					(size 1.27 1.27)
				)
			)
		)
		(duplicate_pad_numbers_are_jumpers no)
		(fp_line
			(start 0.7874 0.4064)
			(end -0.7874 0.4064)
			(stroke
				(width 0.1524)
				(type default)
			)
			(layer "F.SilkS")
		)
		(fp_line
			(start 0.7874 -0.4064)
			(end 0.7874 0.4064)
			(stroke
				(width 0.1524)
				(type default)
			)
			(layer "F.SilkS")
		)
		(fp_line
			(start -0.7874 0.4064)
			(end -0.7874 -0.4064)
			(stroke
				(width 0.1524)
				(type default)
			)
			(layer "F.SilkS")
		)
		(fp_line
			(start -0.7874 -0.4064)
			(end 0.7874 -0.4064)
			(stroke
				(width 0.1524)
				(type default)
			)
			(layer "F.SilkS")
		)
		(fp_line
			(start 0.67945 0.3048)
			(end 0.120396 0.3048)
			(stroke
				(width 0.1)
				(type default)
			)
			(layer "F.Fab")
		)
		(fp_line
			(start 0.67945 -0.3048)
			(end 0.67945 0.3048)
			(stroke
				(width 0.1)
				(type default)
			)
			(layer "F.Fab")
		)
		(fp_line
			(start 0.12065 -0.2794)
			(end 0.12065 -0.3048)
			(stroke
				(width 0.1)
				(type default)
			)
			(layer "F.Fab")
		)
		(fp_line
			(start 0.12065 -0.3048)
			(end 0.67945 -0.3048)
			(stroke
				(width 0.1)
				(type default)
			)
			(layer "F.Fab")
		)
		(fp_line
			(start 0.120396 0.3048)
			(end 0.120396 0.2794)
			(stroke
				(width 0.1)
				(type default)
			)
			(layer "F.Fab")
		)
		(fp_line
			(start 0.120396 0.2794)
			(end -0.12065 0.2794)
			(stroke
				(width 0.1)
				(type default)
			)
			(layer "F.Fab")
		)
		(fp_line
			(start -0.12065 0.3048)
			(end -0.67945 0.3048)
			(stroke
				(width 0.1)
				(type default)
			)
			(layer "F.Fab")
		)
		(fp_line
			(start -0.12065 0.2794)
			(end -0.12065 0.3048)
			(stroke
				(width 0.1)
				(type default)
			)
			(layer "F.Fab")
		)
		(fp_line
			(start -0.12065 -0.2794)
			(end 0.12065 -0.2794)
			(stroke
				(width 0.1)
				(type default)
			)
			(layer "F.Fab")
		)
		(fp_line
			(start -0.12065 -0.305054)
			(end -0.12065 -0.2794)
			(stroke
				(width 0.1)
				(type default)
			)
			(layer "F.Fab")
		)
		(fp_line
			(start -0.67945 0.3048)
			(end -0.67945 -0.305054)
			(stroke
				(width 0.1)
				(type default)
			)
			(layer "F.Fab")
		)
		(fp_line
			(start -0.67945 -0.305054)
			(end -0.12065 -0.305054)
			(stroke
				(width 0.1)
				(type default)
			)
			(layer "F.Fab")
		)
		(pad "1" smd circle
			(at -0.40005 0 180)
			(size 0 0)
			(layers "F.Cu" "F.Mask" "F.Paste")
			(net "USB_HUB2_MRP_PROG_FUNC6")
		)
		(pad "2" smd circle
			(at 0.40005 0 180)
			(size 0 0)
			(layers "F.Cu" "F.Mask" "F.Paste")
			(net "GND")
		)
	)
	(footprint ""
		(layer "F.Cu")
		(at 358.797098 -257.744976)
		(property "Reference" "C2572"
			(at 0 0 0)
			(layer "F.SilkS")
			(hide yes)
			(effects
				(font
					(size 1.27 1.27)
				)
			)
		)
		(property "Value" ""
			(at 0 0 0)
			(layer "F.Fab")
			(effects
				(font
					(size 1.27 1.27)
				)
			)
		)
		(duplicate_pad_numbers_are_jumpers no)
		(fp_line
			(start -0.7874 -0.4064)
			(end 0.7874 -0.4064)
			(stroke
				(width 0.1524)
				(type default)
			)
			(layer "F.SilkS")
		)
		(fp_line
			(start -0.7874 0.4064)
			(end -0.7874 -0.4064)
			(stroke
				(width 0.1524)
				(type default)
			)
			(layer "F.SilkS")
		)
		(fp_line
			(start 0.7874 -0.4064)
			(end 0.7874 0.4064)
			(stroke
				(width 0.1524)
				(type default)
			)
			(layer "F.SilkS")
		)
		(fp_line
			(start 0.7874 0.4064)
			(end -0.7874 0.4064)
			(stroke
				(width 0.1524)
				(type default)
			)
			(layer "F.SilkS")
		)
		(fp_line
			(start -0.67945 -0.305054)
			(end -0.12065 -0.305054)
			(stroke
				(width 0.1)
				(type default)
			)
			(layer "F.Fab")
		)
		(fp_line
			(start -0.67945 0.3048)
			(end -0.67945 -0.305054)
			(stroke
				(width 0.1)
				(type default)
			)
			(layer "F.Fab")
		)
		(fp_line
			(start -0.12065 -0.305054)
			(end -0.12065 -0.2794)
			(stroke
				(width 0.1)
				(type default)
			)
			(layer "F.Fab")
		)
		(fp_line
			(start -0.12065 -0.2794)
			(end 0.12065 -0.2794)
			(stroke
				(width 0.1)
				(type default)
			)
			(layer "F.Fab")
		)
		(fp_line
			(start -0.12065 0.2794)
			(end -0.12065 0.3048)
			(stroke
				(width 0.1)
				(type default)
			)
			(layer "F.Fab")
		)
		(fp_line
			(start -0.12065 0.3048)
			(end -0.67945 0.3048)
			(stroke
				(width 0.1)
				(type default)
			)
			(layer "F.Fab")
		)
		(fp_line
			(start 0.120396 0.2794)
			(end -0.12065 0.2794)
			(stroke
				(width 0.1)
				(type default)
			)
			(layer "F.Fab")
		)
		(fp_line
			(start 0.120396 0.3048)
			(end 0.120396 0.2794)
			(stroke
				(width 0.1)
				(type default)
			)
			(layer "F.Fab")
		)
		(fp_line
			(start 0.12065 -0.3048)
			(end 0.67945 -0.3048)
			(stroke
				(width 0.1)
				(type default)
			)
			(layer "F.Fab")
		)
		(fp_line
			(start 0.12065 -0.2794)
			(end 0.12065 -0.3048)
			(stroke
				(width 0.1)
				(type default)
			)
			(layer "F.Fab")
		)
		(fp_line
			(start 0.67945 -0.3048)
			(end 0.67945 0.3048)
			(stroke
				(width 0.1)
				(type default)
			)
			(layer "F.Fab")
		)
		(fp_line
			(start 0.67945 0.3048)
			(end 0.120396 0.3048)
			(stroke
				(width 0.1)
				(type default)
			)
			(layer "F.Fab")
		)
		(pad "1" smd circle
			(at -0.40005 0)
			(size 0 0)
			(layers "F.Cu" "F.Mask" "F.Paste")
			(net "PVDDCR_SOC_P0")
		)
		(pad "2" smd circle
			(at 0.40005 0)
			(size 0 0)
			(layers "F.Cu" "F.Mask" "F.Paste")
			(net "GND")
		)
	)
)
